(kicad_pcb
	(version 20260206)
	(generator "pcbnew")
	(generator_version "10.0")
	(general
		(thickness 1.6)
		(legacy_teardrops no)
	)
	(paper "A4")
	(title_block
		(title "03242023_DA0F0TMBIJ0_F0T_Motherboard_J_brd_V01_OCP.brd")
		(comment 1 "Grand Teton / footprints 2911-2911 of 6105")
	)
	(layers
		(0 "F.Cu" signal "TOP")
		(4 "In1.Cu" signal "GND")
		(6 "In2.Cu" signal "IN1")
		(8 "In3.Cu" signal "GND1")
		(10 "In4.Cu" signal "IN2")
		(12 "In5.Cu" signal "GND2")
		(14 "In6.Cu" signal "IN3")
		(16 "In7.Cu" signal "GND3")
		(18 "In8.Cu" signal "VCC")
		(20 "In9.Cu" signal "VCC1")
		(22 "In10.Cu" signal "GND4")
		(24 "In11.Cu" signal "IN4")
		(26 "In12.Cu" signal "GND5")
		(28 "In13.Cu" signal "IN5")
		(30 "In14.Cu" signal "GND6")
		(32 "In15.Cu" signal "IN6")
		(34 "In16.Cu" signal "GND7")
		(2 "B.Cu" signal "BOTTOM")
		(9 "F.Adhes" user "F.Adhesive")
		(11 "B.Adhes" user "B.Adhesive")
		(13 "F.Paste" user "Package Geometry/Pastemask Top")
		(15 "B.Paste" user "Package Geometry/Pastemask Bottom")
		(5 "F.SilkS" user "Ref Des/Silkscreen Top")
		(7 "B.SilkS" user "Ref Des/Silkscreen Bottom")
		(1 "F.Mask" user "Board Geometry/Soldermask Top")
		(3 "B.Mask" user "Board Geometry/Soldermask Bottom")
		(17 "Dwgs.User" user "User.Drawings")
		(19 "Cmts.User" user "User.Comments")
		(21 "Eco1.User" user "User.Eco1")
		(23 "Eco2.User" user "User.Eco2")
		(25 "Edge.Cuts" user "Board Geometry/Outline")
		(27 "Margin" user)
		(31 "F.CrtYd" user "Package Geometry/Place Bound Top")
		(29 "B.CrtYd" user "Package Geometry/Place Bound Bottom")
		(35 "F.Fab" user "Ref Des/Assembly Top")
		(33 "B.Fab" user "Ref Des/Assembly Bottom")
	)
	(footprint ""
		(layer "F.Cu")
		(at 12.786106 -106.30408 -90)
		(property "Reference" "R2789"
			(at 0 0 270)
			(layer "F.SilkS")
			(hide yes)
			(effects
				(font
					(size 1.27 1.27)
				)
			)
		)
		(property "Value" ""
			(at 0 0 270)
			(layer "F.Fab")
			(effects
				(font
					(size 1.27 1.27)
				)
			)
		)
		(duplicate_pad_numbers_are_jumpers no)
		(fp_line
			(start -0.00254 0.4064)
			(end -0.7874 0.4064)
			(stroke
				(width 0.1524)
				(type default)
			)
			(layer "F.SilkS")
		)
		(fp_line
			(start -0.7874 -0.4064)
			(end 0.7874 -0.4064)
			(stroke
				(width 0.1524)
				(type default)
			)
			(layer "F.SilkS")
		)
		(fp_line
			(start 0.7874 -0.4064)
			(end 0.7874 0.4064)
			(stroke
				(width 0.1524)
				(type default)
			)
			(layer "F.SilkS")
		)
		(fp_line
			(start -0.67945 0.3048)
			(end -0.67945 -0.305054)
			(stroke
				(width 0.1)
				(type default)
			)
			(layer "F.Fab")
		)
		(fp_line
			(start -0.12065 0.3048)
			(end -0.67945 0.3048)
			(stroke
				(width 0.1)
				(type default)
			)
			(layer "F.Fab")
		)
		(fp_line
			(start 0.120396 0.3048)
			(end 0.120396 0.2794)
			(stroke
				(width 0.1)
				(type default)
			)
			(layer "F.Fab")
		)
		(fp_line
			(start 0.67945 0.3048)
			(end 0.120396 0.3048)
			(stroke
				(width 0.1)
				(type default)
			)
			(layer "F.Fab")
		)
		(fp_line
			(start -0.12065 0.2794)
			(end -0.12065 0.3048)
			(stroke
				(width 0.1)
				(type default)
			)
			(layer "F.Fab")
		)
		(fp_line
			(start 0.120396 0.2794)
			(end -0.12065 0.2794)
			(stroke
				(width 0.1)
				(type default)
			)
			(layer "F.Fab")
		)
		(fp_line
			(start -0.12065 -0.2794)
			(end 0.12065 -0.2794)
			(stroke
				(width 0.1)
				(type default)
			)
			(layer "F.Fab")
		)
		(fp_line
			(start 0.12065 -0.2794)
			(end 0.12065 -0.3048)
			(stroke
				(width 0.1)
				(type default)
			)
			(layer "F.Fab")
		)
		(fp_line
			(start 0.12065 -0.3048)
			(end 0.67945 -0.3048)
			(stroke
				(width 0.1)
				(type default)
			)
			(layer "F.Fab")
		)
		(fp_line
			(start 0.67945 -0.3048)
			(end 0.67945 0.3048)
			(stroke
				(width 0.1)
				(type default)
			)
			(layer "F.Fab")
		)
		(fp_line
			(start -0.67945 -0.305054)
			(end -0.12065 -0.305054)
			(stroke
				(width 0.1)
				(type default)
			)
			(layer "F.Fab")
		)
		(fp_line
			(start -0.12065 -0.305054)
			(end -0.12065 -0.2794)
			(stroke
				(width 0.1)
				(type default)
			)
			(layer "F.Fab")
		)
		(pad "1" smd rect
			(at -0.40005 0 90)
			(size 0.4572 0.508)
			(layers "F.Cu" "F.Mask" "F.Paste")
			(net "USB2_HOST_BMC_B_BUF_DN")
		)
		(pad "2" smd rect
			(at 0.40005 0 90)
			(size 0.4572 0.508)
			(layers "F.Cu" "F.Mask" "F.Paste")
			(net "USB2_HUB_BUF_SWB_R_DN")
		)
	)
)
